# BASEBOARD_FAB2 (Tioga Pass) — schematic netlist excerpt (pin names and nets, part order shuffled) for the footprints in the layout excerpt that follows; sources: Cadence DE-HDL packaged netlist, KiCad conversion of Wiwynn_Tioga_Pass_MB.brd

R3L1  RES  0.0 5% CHIP  pkg 0402  page 236 : A = VR_PVNN_PCH_PH1_VCIN ; B = P5V_STBY
R7P27  RES  150.0 1% CHIP  pkg 0402  page 92 : A = PVCCIO_CPU0 ; B = H_CPU1_MSMI_G_N

(kicad_pcb
	(version 20260206)
	(generator "pcbnew")
	(generator_version "10.0")
	(general
		(thickness 1.6)
		(legacy_teardrops no)
	)
	(paper "A4")
	(title_block
		(title "Wiwynn_Tioga_Pass_MB.brd")
		(comment 1 "Tioga Pass / footprints 2414-2416 of 4770")
	)
	(layers
		(0 "F.Cu" signal "TOP")
		(4 "In1.Cu" signal "L2GND")
		(6 "In2.Cu" signal "L3")
		(8 "In3.Cu" signal "L4GND")
		(10 "In4.Cu" signal "L5")
		(12 "In5.Cu" signal "L6GND")
		(14 "In6.Cu" signal "L7VCC")
		(16 "In7.Cu" signal "L8VCC")
		(18 "In8.Cu" signal "L9GND")
		(20 "In9.Cu" signal "L10")
		(22 "In10.Cu" signal "L11GND")
		(24 "In11.Cu" signal "L12")
		(26 "In12.Cu" signal "L13GND")
		(2 "B.Cu" signal "BOTTOM")
		(9 "F.Adhes" user "F.Adhesive")
		(11 "B.Adhes" user "B.Adhesive")
		(13 "F.Paste" user "Package Geometry/Pastemask Top")
		(15 "B.Paste" user "Package Geometry/Pastemask Bottom")
		(5 "F.SilkS" user "Ref Des/Silkscreen Top")
		(7 "B.SilkS" user "Ref Des/Silkscreen Bottom")
		(1 "F.Mask" user "Board Geometry/Soldermask Top")
		(3 "B.Mask" user "Board Geometry/Soldermask Bottom")
		(17 "Dwgs.User" user "User.Drawings")
		(19 "Cmts.User" user "User.Comments")
		(21 "Eco1.User" user "User.Eco1")
		(23 "Eco2.User" user "User.Eco2")
		(25 "Edge.Cuts" user "Board Geometry/Outline")
		(27 "Margin" user)
		(31 "F.CrtYd" user "Package Geometry/Place Bound Top")
		(29 "B.CrtYd" user "Package Geometry/Place Bound Bottom")
		(35 "F.Fab" user "Ref Des/Assembly Top")
		(33 "B.Fab" user "Ref Des/Assembly Bottom")
	)
	(footprint ""
		(layer "B.Cu")
		(at 373.9642 -155.432506)
		(property "Reference" "R3L1"
			(at 0 0 0)
			(layer "B.SilkS")
			(hide yes)
			(effects
				(font
					(size 1.27 1.27)
				)
				(justify mirror)
			)
		)
		(property "Value" ""
			(at 0 0 0)
			(layer "B.Fab")
			(effects
				(font
					(size 1.27 1.27)
				)
				(justify mirror)
			)
		)
		(duplicate_pad_numbers_are_jumpers no)
		(fp_poly
			(pts
				(xy 0.2794 -0.1016) (xy -0.2794 -0.1016) (xy -0.2794 0.9906) (xy 0.2794 0.9906)
			)
			(stroke
				(width 0)
				(type default)
			)
			(fill no)
			(layer "B.CrtYd")
		)
		(fp_line
			(start -0.2794 -0.1016)
			(end 0.2794 -0.1016)
			(stroke
				(width 0.1)
				(type default)
			)
			(layer "B.Fab")
		)
		(fp_line
			(start -0.2794 0.9906)
			(end -0.2794 -0.1016)
			(stroke
				(width 0.1)
				(type default)
			)
			(layer "B.Fab")
		)
		(fp_line
			(start 0.2794 -0.1016)
			(end 0.2794 0.9906)
			(stroke
				(width 0.1)
				(type default)
			)
			(layer "B.Fab")
		)
		(fp_line
			(start 0.2794 0.9906)
			(end -0.2794 0.9906)
			(stroke
				(width 0.1)
				(type default)
			)
			(layer "B.Fab")
		)
		(pad "1" smd rect
			(at 0 0 180)
			(size 0.508 0.508)
			(layers "B.Cu" "B.Mask" "B.Paste")
			(net "VR_PVNN_PCH_PH1_VCIN")
		)
		(pad "2" smd rect
			(at 0 0.889 180)
			(size 0.508 0.508)
			(layers "B.Cu" "B.Mask" "B.Paste")
			(net "P5V_STBY")
		)
		(zone
			(layer "B.Cu")
			(hatch none 0.5)
			(connect_pads
				(clearance 0)
			)
			(min_thickness 0.25)
			(keepout
				(tracks allowed)
				(vias not_allowed)
				(pads allowed)
				(copperpour not_allowed)
				(footprints allowed)
			)
			(placement
				(enabled no)
				(sheetname "")
			)
			(fill
				(thermal_gap 0.5)
				(thermal_bridge_width 0.5)
				(island_removal_mode 0)
			)
			(polygon
				(pts
					(xy 374.2182 -155.178506) (xy 373.7102 -155.178506) (xy 373.7102 -154.797506) (xy 374.2182 -154.797506)
				)
			)
		)
		(zone
			(layer "B.Cu")
			(hatch none 0.5)
			(connect_pads
				(clearance 0)
			)
			(min_thickness 0.25)
			(keepout
				(tracks not_allowed)
				(vias allowed)
				(pads allowed)
				(copperpour not_allowed)
				(footprints allowed)
			)
			(placement
				(enabled no)
				(sheetname "")
			)
			(fill
				(thermal_gap 0.5)
				(thermal_bridge_width 0.5)
				(island_removal_mode 0)
			)
			(polygon
				(pts
					(xy 374.2182 -154.797506) (xy 373.7102 -154.797506) (xy 373.7102 -155.178506) (xy 374.2182 -155.178506)
				)
			)
		)
	)
	(footprint ""
		(layer "B.Cu")
		(at 60.28182 -103.87584)
		(property "Reference" ""
			(at 0 0 0)
			(layer "B.SilkS")
			(hide yes)
			(effects
				(font
					(size 1.27 1.27)
				)
				(justify mirror)
			)
		)
		(property "Value" ""
			(at 0 0 0)
			(layer "B.Fab")
			(effects
				(font
					(size 1.27 1.27)
				)
				(justify mirror)
			)
		)
		(duplicate_pad_numbers_are_jumpers no)
		(fp_poly
			(pts
				(arc
					(start 2.032 0)
					(mid -2.032 0)
					(end 2.032 0)
				)
			)
			(stroke
				(width 0)
				(type default)
			)
			(fill no)
			(layer "B.CrtYd")
		)
		(pad "1" smd circle
			(at 0 0 180)
			(size 1.016 1.016)
			(layers "B.Cu" "B.Mask" "B.Paste")
			(net "Net_387")
		)
		(zone
			(layers "F.Cu" "B.Cu" "In1.Cu" "In2.Cu" "In3.Cu" "In4.Cu" "In5.Cu" "In6.Cu"
				"In7.Cu" "In8.Cu" "In9.Cu" "In10.Cu" "In11.Cu" "In12.Cu"
			)
			(hatch none 0.5)
			(connect_pads
				(clearance 0)
			)
			(min_thickness 0.25)
			(keepout
				(tracks allowed)
				(vias not_allowed)
				(pads allowed)
				(copperpour not_allowed)
				(footprints allowed)
			)
			(placement
				(enabled no)
				(sheetname "")
			)
			(fill
				(thermal_gap 0.5)
				(thermal_bridge_width 0.5)
				(island_removal_mode 0)
			)
			(polygon
				(pts
					(arc
						(start 61.80582 -103.87584)
						(mid 58.75782 -103.87584)
						(end 61.80582 -103.87584)
					)
				)
			)
		)
		(zone
			(layer "B.Cu")
			(hatch none 0.5)
			(connect_pads
				(clearance 0)
			)
			(min_thickness 0.25)
			(keepout
				(tracks not_allowed)
				(vias allowed)
				(pads allowed)
				(copperpour not_allowed)
				(footprints allowed)
			)
			(placement
				(enabled no)
				(sheetname "")
			)
			(fill
				(thermal_gap 0.5)
				(thermal_bridge_width 0.5)
				(island_removal_mode 0)
			)
			(polygon
				(pts
					(arc
						(start 61.80582 -103.87584)
						(mid 58.75782 -103.87584)
						(end 61.80582 -103.87584)
					)
				)
			)
		)
	)
	(footprint ""
		(layer "B.Cu")
		(at 128.8796 -66.292984 180)
		(property "Reference" "R7P27"
			(at 0 0 0)
			(layer "B.SilkS")
			(hide yes)
			(effects
				(font
					(size 1.27 1.27)
				)
				(justify mirror)
			)
		)
		(property "Value" ""
			(at 0 0 0)
			(layer "B.Fab")
			(effects
				(font
					(size 1.27 1.27)
				)
				(justify mirror)
			)
		)
		(duplicate_pad_numbers_are_jumpers no)
		(fp_poly
			(pts
				(xy 0.2794 -0.1016) (xy -0.2794 -0.1016) (xy -0.2794 0.9906) (xy 0.2794 0.9906)
			)
			(stroke
				(width 0)
				(type default)
			)
			(fill no)
			(layer "B.CrtYd")
		)
		(fp_line
			(start 0.2794 0.9906)
			(end -0.2794 0.9906)
			(stroke
				(width 0.1)
				(type default)
			)
			(layer "B.Fab")
		)
		(fp_line
			(start 0.2794 -0.1016)
			(end 0.2794 0.9906)
			(stroke
				(width 0.1)
				(type default)
			)
			(layer "B.Fab")
		)
		(fp_line
			(start -0.2794 0.9906)
			(end -0.2794 -0.1016)
			(stroke
				(width 0.1)
				(type default)
			)
			(layer "B.Fab")
		)
		(fp_line
			(start -0.2794 -0.1016)
			(end 0.2794 -0.1016)
			(stroke
				(width 0.1)
				(type default)
			)
			(layer "B.Fab")
		)
		(pad "1" smd rect
			(at 0 0)
			(size 0.508 0.508)
			(layers "B.Cu" "B.Mask" "B.Paste")
			(net "PVCCIO_CPU0")
		)
		(pad "2" smd rect
			(at 0 0.889)
			(size 0.508 0.508)
			(layers "B.Cu" "B.Mask" "B.Paste")
			(net "H_CPU1_MSMI_G_N")
		)
		(zone
			(layer "B.Cu")
			(hatch none 0.5)
			(connect_pads
				(clearance 0)
			)
			(min_thickness 0.25)
			(keepout
				(tracks not_allowed)
				(vias allowed)
				(pads allowed)
				(copperpour not_allowed)
				(footprints allowed)
			)
			(placement
				(enabled no)
				(sheetname "")
			)
			(fill
				(thermal_gap 0.5)
				(thermal_bridge_width 0.5)
				(island_removal_mode 0)
			)
			(polygon
				(pts
					(xy 128.6256 -66.927984) (xy 129.1336 -66.927984) (xy 129.1336 -66.546984) (xy 128.6256 -66.546984)
				)
			)
		)
		(zone
			(layer "B.Cu")
			(hatch none 0.5)
			(connect_pads
				(clearance 0)
			)
			(min_thickness 0.25)
			(keepout
				(tracks allowed)
				(vias not_allowed)
				(pads allowed)
				(copperpour not_allowed)
				(footprints allowed)
			)
			(placement
				(enabled no)
				(sheetname "")
			)
			(fill
				(thermal_gap 0.5)
				(thermal_bridge_width 0.5)
				(island_removal_mode 0)
			)
			(polygon
				(pts
					(xy 128.6256 -66.546984) (xy 129.1336 -66.546984) (xy 129.1336 -66.927984) (xy 128.6256 -66.927984)
				)
			)
		)
	)
)
